# T6G (Grand Teton) — schematic netlist excerpt (pin names and nets, part order shuffled) for the footprints in the layout excerpt that follows; sources: Cadence DE-HDL packaged netlist, KiCad conversion of 04192023_DAF0TMB3IC0_F0TG_MB_C_brd_V02_OCP.brd

C2546  Q_CAP  22UF 4V 20% X6S  pkg C0402  page 70 : A = PVDDCR_SOC_P0 ; B = GND
C344  Q_CAP  0.1UF 10V 10% X7S  pkg C0201  page 334 : A = P0V9_CPU1_RT1_2A ; B = GND
C6072  Q_CAP  0.01UF 50V 10% X7R  pkg C0402  page 177 : A = P1V2_AUX ; B = GND

(kicad_pcb
	(version 20260206)
	(generator "pcbnew")
	(generator_version "10.0")
	(general
		(thickness 1.6)
		(legacy_teardrops no)
	)
	(paper "A4")
	(title_block
		(title "04192023_DAF0TMB3IC0_F0TG_MB_C_brd_V02_OCP.brd")
		(comment 1 "Grand Teton / footprints 7357-7359 of 8354")
	)
	(layers
		(0 "F.Cu" signal "TOP")
		(4 "In1.Cu" signal "GND")
		(6 "In2.Cu" signal "IN1")
		(8 "In3.Cu" signal "GND1")
		(10 "In4.Cu" signal "IN2")
		(12 "In5.Cu" signal "GND2")
		(14 "In6.Cu" signal "IN3")
		(16 "In7.Cu" signal "GND3")
		(18 "In8.Cu" signal "VCC")
		(20 "In9.Cu" signal "VCC1")
		(22 "In10.Cu" signal "GND4")
		(24 "In11.Cu" signal "IN4")
		(26 "In12.Cu" signal "GND5")
		(28 "In13.Cu" signal "IN5")
		(30 "In14.Cu" signal "GND6")
		(32 "In15.Cu" signal "IN6")
		(34 "In16.Cu" signal "GND7")
		(2 "B.Cu" signal "BOTTOM")
		(9 "F.Adhes" user "F.Adhesive")
		(11 "B.Adhes" user "B.Adhesive")
		(13 "F.Paste" user "Package Geometry/Pastemask Top")
		(15 "B.Paste" user "Package Geometry/Pastemask Bottom")
		(5 "F.SilkS" user "Ref Des/Silkscreen Top")
		(7 "B.SilkS" user "Ref Des/Silkscreen Bottom")
		(1 "F.Mask" user "Board Geometry/Soldermask Top")
		(3 "B.Mask" user "Board Geometry/Soldermask Bottom")
		(17 "Dwgs.User" user "User.Drawings")
		(19 "Cmts.User" user "User.Comments")
		(21 "Eco1.User" user "User.Eco1")
		(23 "Eco2.User" user "User.Eco2")
		(25 "Edge.Cuts" user "Board Geometry/Outline")
		(27 "Margin" user)
		(31 "F.CrtYd" user "Package Geometry/Place Bound Top")
		(29 "B.CrtYd" user "Package Geometry/Place Bound Bottom")
		(35 "F.Fab" user "Ref Des/Assembly Top")
		(33 "B.Fab" user "Ref Des/Assembly Bottom")
	)
	(footprint ""
		(layer "B.Cu")
		(at 357.515922 -256.012188 -90)
		(property "Reference" "C2546"
			(at 0 0 90)
			(layer "B.SilkS")
			(hide yes)
			(effects
				(font
					(size 1.27 1.27)
				)
				(justify mirror)
			)
		)
		(property "Value" ""
			(at 0 0 90)
			(layer "B.Fab")
			(effects
				(font
					(size 1.27 1.27)
				)
				(justify mirror)
			)
		)
		(duplicate_pad_numbers_are_jumpers no)
		(fp_line
			(start -0.7874 0.4064)
			(end 0.7874 0.4064)
			(stroke
				(width 0.1524)
				(type default)
			)
			(layer "B.SilkS")
		)
		(fp_line
			(start 0.7874 0.4064)
			(end 0.7874 -0.4064)
			(stroke
				(width 0.1524)
				(type default)
			)
			(layer "B.SilkS")
		)
		(fp_line
			(start -0.7874 -0.4064)
			(end -0.7874 0.4064)
			(stroke
				(width 0.1524)
				(type default)
			)
			(layer "B.SilkS")
		)
		(fp_line
			(start 0.7874 -0.4064)
			(end -0.7874 -0.4064)
			(stroke
				(width 0.1524)
				(type default)
			)
			(layer "B.SilkS")
		)
		(fp_line
			(start -0.67945 0.3048)
			(end -0.120396 0.3048)
			(stroke
				(width 0.1)
				(type default)
			)
			(layer "B.Fab")
		)
		(fp_line
			(start -0.120396 0.3048)
			(end -0.120396 0.2794)
			(stroke
				(width 0.1)
				(type default)
			)
			(layer "B.Fab")
		)
		(fp_line
			(start 0.12065 0.3048)
			(end 0.67945 0.3048)
			(stroke
				(width 0.1)
				(type default)
			)
			(layer "B.Fab")
		)
		(fp_line
			(start 0.67945 0.3048)
			(end 0.67945 -0.305054)
			(stroke
				(width 0.1)
				(type default)
			)
			(layer "B.Fab")
		)
		(fp_line
			(start -0.120396 0.2794)
			(end 0.12065 0.2794)
			(stroke
				(width 0.1)
				(type default)
			)
			(layer "B.Fab")
		)
		(fp_line
			(start 0.12065 0.2794)
			(end 0.12065 0.3048)
			(stroke
				(width 0.1)
				(type default)
			)
			(layer "B.Fab")
		)
		(fp_line
			(start -0.12065 -0.2794)
			(end -0.12065 -0.3048)
			(stroke
				(width 0.1)
				(type default)
			)
			(layer "B.Fab")
		)
		(fp_line
			(start 0.12065 -0.2794)
			(end -0.12065 -0.2794)
			(stroke
				(width 0.1)
				(type default)
			)
			(layer "B.Fab")
		)
		(fp_line
			(start -0.67945 -0.3048)
			(end -0.67945 0.3048)
			(stroke
				(width 0.1)
				(type default)
			)
			(layer "B.Fab")
		)
		(fp_line
			(start -0.12065 -0.3048)
			(end -0.67945 -0.3048)
			(stroke
				(width 0.1)
				(type default)
			)
			(layer "B.Fab")
		)
		(fp_line
			(start 0.12065 -0.305054)
			(end 0.12065 -0.2794)
			(stroke
				(width 0.1)
				(type default)
			)
			(layer "B.Fab")
		)
		(fp_line
			(start 0.67945 -0.305054)
			(end 0.12065 -0.305054)
			(stroke
				(width 0.1)
				(type default)
			)
			(layer "B.Fab")
		)
		(pad "1" smd circle
			(at 0.40005 0 90)
			(size 0 0)
			(layers "B.Cu" "B.Mask" "B.Paste")
			(net "PVDDCR_SOC_P0")
		)
		(pad "2" smd circle
			(at -0.40005 0 90)
			(size 0 0)
			(layers "B.Cu" "B.Mask" "B.Paste")
			(net "GND")
		)
	)
	(footprint ""
		(layer "B.Cu")
		(at 128.811528 -39.090092 180)
		(property "Reference" "C6072"
			(at 0 0 0)
			(layer "B.SilkS")
			(hide yes)
			(effects
				(font
					(size 1.27 1.27)
				)
				(justify mirror)
			)
		)
		(property "Value" ""
			(at 0 0 0)
			(layer "B.Fab")
			(effects
				(font
					(size 1.27 1.27)
				)
				(justify mirror)
			)
		)
		(duplicate_pad_numbers_are_jumpers no)
		(fp_line
			(start 0.7874 0.4064)
			(end 0.7874 -0.4064)
			(stroke
				(width 0.1524)
				(type default)
			)
			(layer "B.SilkS")
		)
		(fp_line
			(start 0.7874 -0.4064)
			(end -0.7874 -0.4064)
			(stroke
				(width 0.1524)
				(type default)
			)
			(layer "B.SilkS")
		)
		(fp_line
			(start -0.7874 0.4064)
			(end 0.7874 0.4064)
			(stroke
				(width 0.1524)
				(type default)
			)
			(layer "B.SilkS")
		)
		(fp_line
			(start -0.7874 -0.4064)
			(end -0.7874 0.4064)
			(stroke
				(width 0.1524)
				(type default)
			)
			(layer "B.SilkS")
		)
		(fp_line
			(start 0.67945 0.3048)
			(end 0.67945 -0.305054)
			(stroke
				(width 0.1)
				(type default)
			)
			(layer "B.Fab")
		)
		(fp_line
			(start 0.67945 -0.305054)
			(end 0.12065 -0.305054)
			(stroke
				(width 0.1)
				(type default)
			)
			(layer "B.Fab")
		)
		(fp_line
			(start 0.12065 0.3048)
			(end 0.67945 0.3048)
			(stroke
				(width 0.1)
				(type default)
			)
			(layer "B.Fab")
		)
		(fp_line
			(start 0.12065 0.2794)
			(end 0.12065 0.3048)
			(stroke
				(width 0.1)
				(type default)
			)
			(layer "B.Fab")
		)
		(fp_line
			(start 0.12065 -0.2794)
			(end -0.12065 -0.2794)
			(stroke
				(width 0.1)
				(type default)
			)
			(layer "B.Fab")
		)
		(fp_line
			(start 0.12065 -0.305054)
			(end 0.12065 -0.2794)
			(stroke
				(width 0.1)
				(type default)
			)
			(layer "B.Fab")
		)
		(fp_line
			(start -0.120396 0.3048)
			(end -0.120396 0.2794)
			(stroke
				(width 0.1)
				(type default)
			)
			(layer "B.Fab")
		)
		(fp_line
			(start -0.120396 0.2794)
			(end 0.12065 0.2794)
			(stroke
				(width 0.1)
				(type default)
			)
			(layer "B.Fab")
		)
		(fp_line
			(start -0.12065 -0.2794)
			(end -0.12065 -0.3048)
			(stroke
				(width 0.1)
				(type default)
			)
			(layer "B.Fab")
		)
		(fp_line
			(start -0.12065 -0.3048)
			(end -0.67945 -0.3048)
			(stroke
				(width 0.1)
				(type default)
			)
			(layer "B.Fab")
		)
		(fp_line
			(start -0.67945 0.3048)
			(end -0.120396 0.3048)
			(stroke
				(width 0.1)
				(type default)
			)
			(layer "B.Fab")
		)
		(fp_line
			(start -0.67945 -0.3048)
			(end -0.67945 0.3048)
			(stroke
				(width 0.1)
				(type default)
			)
			(layer "B.Fab")
		)
		(pad "1" smd circle
			(at 0.40005 0)
			(size 0 0)
			(layers "B.Cu" "B.Mask" "B.Paste")
			(net "P1V2_AUX")
		)
		(pad "2" smd circle
			(at -0.40005 0)
			(size 0 0)
			(layers "B.Cu" "B.Mask" "B.Paste")
			(net "GND")
		)
	)
	(footprint ""
		(layer "B.Cu")
		(at 95.64624 -388.011162 -90)
		(property "Reference" "C344"
			(at 0 0 90)
			(layer "B.SilkS")
			(hide yes)
			(effects
				(font
					(size 1.27 1.27)
				)
				(justify mirror)
			)
		)
		(property "Value" ""
			(at 0 0 90)
			(layer "B.Fab")
			(effects
				(font
					(size 1.27 1.27)
				)
				(justify mirror)
			)
		)
		(duplicate_pad_numbers_are_jumpers no)
		(fp_line
			(start -0.299974 0.150114)
			(end 0.299974 0.150114)
			(stroke
				(width 0.1)
				(type default)
			)
			(layer "B.Fab")
		)
		(fp_line
			(start 0.299974 0.150114)
			(end 0.299974 -0.150114)
			(stroke
				(width 0.1)
				(type default)
			)
			(layer "B.Fab")
		)
		(fp_line
			(start -0.299974 -0.150114)
			(end -0.299974 0.150114)
			(stroke
				(width 0.1)
				(type default)
			)
			(layer "B.Fab")
		)
		(fp_line
			(start 0.299974 -0.150114)
			(end -0.299974 -0.150114)
			(stroke
				(width 0.1)
				(type default)
			)
			(layer "B.Fab")
		)
		(pad "1" smd rect
			(at 0.2667 0 90)
			(size 0.3048 0.381)
			(layers "B.Cu" "B.Mask" "B.Paste")
			(net "P0V9_CPU1_RT1_2A")
		)
		(pad "2" smd rect
			(at -0.2667 0 90)
			(size 0.3048 0.381)
			(layers "B.Cu" "B.Mask" "B.Paste")
			(net "GND")
		)
	)
)
